# T6G (Grand Teton) — schematic netlist excerpt (pin names and nets, part order shuffled) for the footprints in the layout excerpt that follows; sources: Cadence DE-HDL packaged netlist, KiCad conversion of 04192023_DAF0TMB3IC0_F0TG_MB_C_brd_V02_OCP.brd

R3859  Q_RES  0 5% EMPTY  pkg 0402LF  page 257 : A = P12V_OCP_V3_2_ISENSE_MAM_MAM ; B = P12V_OCP_V3_2_ISENSE_MAM
C748  Q_CAP_DIFFBUS  DIFF BUS_0.22UF 6.3V 20% X6S  pkg C0201  page 66 : \1\ = P5E_CPU1_P2_TX_C_DN<12> ; \2\ = P5E_CPU1_P2_TX_DN<12>
C115  Q_CAP  22UF 4V 20% X6S  pkg C0402  page 323 : A = P1V8_CPU1_RT_1D ; B = GND

(kicad_pcb
	(version 20260206)
	(generator "pcbnew")
	(generator_version "10.0")
	(general
		(thickness 1.6)
		(legacy_teardrops no)
	)
	(paper "A4")
	(title_block
		(title "04192023_DAF0TMB3IC0_F0TG_MB_C_brd_V02_OCP.brd")
		(comment 1 "Grand Teton / footprints 967-969 of 8354")
	)
	(layers
		(0 "F.Cu" signal "TOP")
		(4 "In1.Cu" signal "GND")
		(6 "In2.Cu" signal "IN1")
		(8 "In3.Cu" signal "GND1")
		(10 "In4.Cu" signal "IN2")
		(12 "In5.Cu" signal "GND2")
		(14 "In6.Cu" signal "IN3")
		(16 "In7.Cu" signal "GND3")
		(18 "In8.Cu" signal "VCC")
		(20 "In9.Cu" signal "VCC1")
		(22 "In10.Cu" signal "GND4")
		(24 "In11.Cu" signal "IN4")
		(26 "In12.Cu" signal "GND5")
		(28 "In13.Cu" signal "IN5")
		(30 "In14.Cu" signal "GND6")
		(32 "In15.Cu" signal "IN6")
		(34 "In16.Cu" signal "GND7")
		(2 "B.Cu" signal "BOTTOM")
		(9 "F.Adhes" user "F.Adhesive")
		(11 "B.Adhes" user "B.Adhesive")
		(13 "F.Paste" user "Package Geometry/Pastemask Top")
		(15 "B.Paste" user "Package Geometry/Pastemask Bottom")
		(5 "F.SilkS" user "Ref Des/Silkscreen Top")
		(7 "B.SilkS" user "Ref Des/Silkscreen Bottom")
		(1 "F.Mask" user "Board Geometry/Soldermask Top")
		(3 "B.Mask" user "Board Geometry/Soldermask Bottom")
		(17 "Dwgs.User" user "User.Drawings")
		(19 "Cmts.User" user "User.Comments")
		(21 "Eco1.User" user "User.Eco1")
		(23 "Eco2.User" user "User.Eco2")
		(25 "Edge.Cuts" user "Board Geometry/Outline")
		(27 "Margin" user)
		(31 "F.CrtYd" user "Package Geometry/Place Bound Top")
		(29 "B.CrtYd" user "Package Geometry/Place Bound Bottom")
		(35 "F.Fab" user "Ref Des/Assembly Top")
		(33 "B.Fab" user "Ref Des/Assembly Bottom")
	)
	(footprint ""
		(layer "F.Cu")
		(at 311.541922 -32.572706)
		(property "Reference" "R3859"
			(at 0 0 0)
			(layer "F.SilkS")
			(hide yes)
			(effects
				(font
					(size 1.27 1.27)
				)
			)
		)
		(property "Value" ""
			(at 0 0 0)
			(layer "F.Fab")
			(effects
				(font
					(size 1.27 1.27)
				)
			)
		)
		(duplicate_pad_numbers_are_jumpers no)
		(fp_line
			(start -0.7874 -0.4064)
			(end 0.7874 -0.4064)
			(stroke
				(width 0.1524)
				(type default)
			)
			(layer "F.SilkS")
		)
		(fp_line
			(start -0.7874 0.4064)
			(end -0.7874 -0.4064)
			(stroke
				(width 0.1524)
				(type default)
			)
			(layer "F.SilkS")
		)
		(fp_line
			(start 0.7874 -0.4064)
			(end 0.7874 0.4064)
			(stroke
				(width 0.1524)
				(type default)
			)
			(layer "F.SilkS")
		)
		(fp_line
			(start 0.7874 0.4064)
			(end -0.7874 0.4064)
			(stroke
				(width 0.1524)
				(type default)
			)
			(layer "F.SilkS")
		)
		(fp_line
			(start -0.67945 -0.305054)
			(end -0.12065 -0.305054)
			(stroke
				(width 0.1)
				(type default)
			)
			(layer "F.Fab")
		)
		(fp_line
			(start -0.67945 0.3048)
			(end -0.67945 -0.305054)
			(stroke
				(width 0.1)
				(type default)
			)
			(layer "F.Fab")
		)
		(fp_line
			(start -0.12065 -0.305054)
			(end -0.12065 -0.2794)
			(stroke
				(width 0.1)
				(type default)
			)
			(layer "F.Fab")
		)
		(fp_line
			(start -0.12065 -0.2794)
			(end 0.12065 -0.2794)
			(stroke
				(width 0.1)
				(type default)
			)
			(layer "F.Fab")
		)
		(fp_line
			(start -0.12065 0.2794)
			(end -0.12065 0.3048)
			(stroke
				(width 0.1)
				(type default)
			)
			(layer "F.Fab")
		)
		(fp_line
			(start -0.12065 0.3048)
			(end -0.67945 0.3048)
			(stroke
				(width 0.1)
				(type default)
			)
			(layer "F.Fab")
		)
		(fp_line
			(start 0.120396 0.2794)
			(end -0.12065 0.2794)
			(stroke
				(width 0.1)
				(type default)
			)
			(layer "F.Fab")
		)
		(fp_line
			(start 0.120396 0.3048)
			(end 0.120396 0.2794)
			(stroke
				(width 0.1)
				(type default)
			)
			(layer "F.Fab")
		)
		(fp_line
			(start 0.12065 -0.3048)
			(end 0.67945 -0.3048)
			(stroke
				(width 0.1)
				(type default)
			)
			(layer "F.Fab")
		)
		(fp_line
			(start 0.12065 -0.2794)
			(end 0.12065 -0.3048)
			(stroke
				(width 0.1)
				(type default)
			)
			(layer "F.Fab")
		)
		(fp_line
			(start 0.67945 -0.3048)
			(end 0.67945 0.3048)
			(stroke
				(width 0.1)
				(type default)
			)
			(layer "F.Fab")
		)
		(fp_line
			(start 0.67945 0.3048)
			(end 0.120396 0.3048)
			(stroke
				(width 0.1)
				(type default)
			)
			(layer "F.Fab")
		)
		(pad "1" smd rect
			(at -0.40005 0 180)
			(size 0.4572 0.508)
			(layers "F.Cu" "F.Mask" "F.Paste")
			(net "P12V_OCP_V3_2_ISENSE_MAM_MAM")
		)
		(pad "2" smd rect
			(at 0.40005 0 180)
			(size 0.4572 0.508)
			(layers "F.Cu" "F.Mask" "F.Paste")
			(net "P12V_OCP_V3_2_ISENSE_MAM")
		)
	)
	(footprint ""
		(layer "F.Cu")
		(at 165.655244 -370.57203 -90)
		(property "Reference" "C748"
			(at 0 0 270)
			(layer "F.SilkS")
			(hide yes)
			(effects
				(font
					(size 1.27 1.27)
				)
			)
		)
		(property "Value" ""
			(at 0 0 270)
			(layer "F.Fab")
			(effects
				(font
					(size 1.27 1.27)
				)
			)
		)
		(duplicate_pad_numbers_are_jumpers no)
		(fp_line
			(start -0.299974 0.150114)
			(end -0.299974 -0.150114)
			(stroke
				(width 0.1)
				(type default)
			)
			(layer "F.Fab")
		)
		(fp_line
			(start 0.299974 0.150114)
			(end -0.299974 0.150114)
			(stroke
				(width 0.1)
				(type default)
			)
			(layer "F.Fab")
		)
		(fp_line
			(start -0.299974 -0.150114)
			(end 0.299974 -0.150114)
			(stroke
				(width 0.1)
				(type default)
			)
			(layer "F.Fab")
		)
		(fp_line
			(start 0.299974 -0.150114)
			(end 0.299974 0.150114)
			(stroke
				(width 0.1)
				(type default)
			)
			(layer "F.Fab")
		)
		(pad "1" smd rect
			(at -0.2667 0 270)
			(size 0.3048 0.381)
			(layers "F.Cu" "F.Mask" "F.Paste")
			(net "P5E_CPU1_P2_TX_C_DN<12>")
		)
		(pad "2" smd rect
			(at 0.2667 0 270)
			(size 0.3048 0.381)
			(layers "F.Cu" "F.Mask" "F.Paste")
			(net "P5E_CPU1_P2_TX_DN<12>")
		)
	)
	(footprint ""
		(layer "F.Cu")
		(at 70.992746 -386.44068 90)
		(property "Reference" "C115"
			(at 0 0 90)
			(layer "F.SilkS")
			(hide yes)
			(effects
				(font
					(size 1.27 1.27)
				)
			)
		)
		(property "Value" ""
			(at 0 0 90)
			(layer "F.Fab")
			(effects
				(font
					(size 1.27 1.27)
				)
			)
		)
		(duplicate_pad_numbers_are_jumpers no)
		(fp_line
			(start 0.7874 -0.4064)
			(end 0.7874 0.4064)
			(stroke
				(width 0.1524)
				(type default)
			)
			(layer "F.SilkS")
		)
		(fp_line
			(start -0.7874 -0.4064)
			(end 0.7874 -0.4064)
			(stroke
				(width 0.1524)
				(type default)
			)
			(layer "F.SilkS")
		)
		(fp_line
			(start 0.7874 0.4064)
			(end -0.7874 0.4064)
			(stroke
				(width 0.1524)
				(type default)
			)
			(layer "F.SilkS")
		)
		(fp_line
			(start -0.7874 0.4064)
			(end -0.7874 -0.4064)
			(stroke
				(width 0.1524)
				(type default)
			)
			(layer "F.SilkS")
		)
		(fp_line
			(start -0.12065 -0.305054)
			(end -0.12065 -0.2794)
			(stroke
				(width 0.1)
				(type default)
			)
			(layer "F.Fab")
		)
		(fp_line
			(start -0.67945 -0.305054)
			(end -0.12065 -0.305054)
			(stroke
				(width 0.1)
				(type default)
			)
			(layer "F.Fab")
		)
		(fp_line
			(start 0.67945 -0.3048)
			(end 0.67945 0.3048)
			(stroke
				(width 0.1)
				(type default)
			)
			(layer "F.Fab")
		)
		(fp_line
			(start 0.12065 -0.3048)
			(end 0.67945 -0.3048)
			(stroke
				(width 0.1)
				(type default)
			)
			(layer "F.Fab")
		)
		(fp_line
			(start 0.12065 -0.2794)
			(end 0.12065 -0.3048)
			(stroke
				(width 0.1)
				(type default)
			)
			(layer "F.Fab")
		)
		(fp_line
			(start -0.12065 -0.2794)
			(end 0.12065 -0.2794)
			(stroke
				(width 0.1)
				(type default)
			)
			(layer "F.Fab")
		)
		(fp_line
			(start 0.120396 0.2794)
			(end -0.12065 0.2794)
			(stroke
				(width 0.1)
				(type default)
			)
			(layer "F.Fab")
		)
		(fp_line
			(start -0.12065 0.2794)
			(end -0.12065 0.3048)
			(stroke
				(width 0.1)
				(type default)
			)
			(layer "F.Fab")
		)
		(fp_line
			(start 0.67945 0.3048)
			(end 0.120396 0.3048)
			(stroke
				(width 0.1)
				(type default)
			)
			(layer "F.Fab")
		)
		(fp_line
			(start 0.120396 0.3048)
			(end 0.120396 0.2794)
			(stroke
				(width 0.1)
				(type default)
			)
			(layer "F.Fab")
		)
		(fp_line
			(start -0.12065 0.3048)
			(end -0.67945 0.3048)
			(stroke
				(width 0.1)
				(type default)
			)
			(layer "F.Fab")
		)
		(fp_line
			(start -0.67945 0.3048)
			(end -0.67945 -0.305054)
			(stroke
				(width 0.1)
				(type default)
			)
			(layer "F.Fab")
		)
		(pad "1" smd circle
			(at -0.40005 0 90)
			(size 0 0)
			(layers "F.Cu" "F.Mask" "F.Paste")
			(net "P1V8_CPU1_RT_1D")
		)
		(pad "2" smd circle
			(at 0.40005 0 90)
			(size 0 0)
			(layers "F.Cu" "F.Mask" "F.Paste")
			(net "GND")
		)
	)
)
